(kicad_pcb
	(version 20260206)
	(generator "pcbnew")
	(generator_version "10.0")
	(general
		(thickness 1.6)
		(legacy_teardrops no)
	)
	(paper "A4")
	(title_block
		(title "12092022_DA0F0TMDCD0_F0T_Management_Board_D_brd_V3_OCP.brd")
		(comment 1 "Grand Teton / footprints 650-654 of 1440")
	)
	(layers
		(0 "F.Cu" signal "TOP")
		(4 "In1.Cu" signal "GND")
		(6 "In2.Cu" signal "IN1")
		(8 "In3.Cu" signal "GND1")
		(10 "In4.Cu" signal "IN2")
		(12 "In5.Cu" signal "VCC")
		(14 "In6.Cu" signal "VCC1")
		(16 "In7.Cu" signal "IN3")
		(18 "In8.Cu" signal "GND2")
		(20 "In9.Cu" signal "IN4")
		(22 "In10.Cu" signal "GND3")
		(2 "B.Cu" signal "BOTTOM")
		(9 "F.Adhes" user "F.Adhesive")
		(11 "B.Adhes" user "B.Adhesive")
		(13 "F.Paste" user "Package Geometry/Pastemask Top")
		(15 "B.Paste" user "Package Geometry/Pastemask Bottom")
		(5 "F.SilkS" user "Ref Des/Silkscreen Top")
		(7 "B.SilkS" user "Ref Des/Silkscreen Bottom")
		(1 "F.Mask" user "Board Geometry/Soldermask Top")
		(3 "B.Mask" user "Board Geometry/Soldermask Bottom")
		(17 "Dwgs.User" user "User.Drawings")
		(19 "Cmts.User" user "User.Comments")
		(21 "Eco1.User" user "User.Eco1")
		(23 "Eco2.User" user "User.Eco2")
		(25 "Edge.Cuts" user "Board Geometry/Outline")
		(27 "Margin" user)
		(31 "F.CrtYd" user "Package Geometry/Place Bound Top")
		(29 "B.CrtYd" user "Package Geometry/Place Bound Bottom")
		(35 "F.Fab" user "Ref Des/Assembly Top")
		(33 "B.Fab" user "Ref Des/Assembly Bottom")
	)
	(footprint ""
		(layer "F.Cu")
		(at 95.911416 -15.895574 90)
		(property "Reference" "J23"
			(at -1.163574 2.794254 90)
			(unlocked yes)
			(layer "F.SilkS")
			(effects
				(font
					(size 0.7874 0.5842)
					(thickness 0.1524)
				)
				(justify left)
			)
		)
		(property "Value" ""
			(at 0 0 90)
			(layer "F.Fab")
			(effects
				(font
					(size 1.27 1.27)
				)
			)
		)
		(duplicate_pad_numbers_are_jumpers no)
		(fp_line
			(start 1.2192 -2.1082)
			(end 1.2192 -0.804672)
			(stroke
				(width 0.1524)
				(type default)
			)
			(layer "F.SilkS")
		)
		(fp_line
			(start -1.2192 -2.1082)
			(end 1.2192 -2.1082)
			(stroke
				(width 0.1524)
				(type default)
			)
			(layer "F.SilkS")
		)
		(fp_line
			(start 1.2192 0.821944)
			(end 1.2192 2.1082)
			(stroke
				(width 0.1524)
				(type default)
			)
			(layer "F.SilkS")
		)
		(fp_line
			(start 1.2192 2.1082)
			(end -1.2192 2.1082)
			(stroke
				(width 0.1524)
				(type default)
			)
			(layer "F.SilkS")
		)
		(fp_line
			(start -1.2192 2.1082)
			(end -1.2192 -2.1082)
			(stroke
				(width 0.1524)
				(type default)
			)
			(layer "F.SilkS")
		)
		(pad "" np_thru_hole circle
			(at -2.8829 -1.27)
			(size 1.0414 1.0414)
			(drill 1.0414)
			(layers "*.Cu" "*.Mask")
			(clearance 0.381)
			(thermal_gap 0.381)
		)
		(pad "" np_thru_hole circle
			(at -2.8829 1.27)
			(size 1.0414 1.0414)
			(drill 1.0414)
			(layers "*.Cu" "*.Mask")
			(clearance 0.381)
			(thermal_gap 0.381)
		)
		(pad "" np_thru_hole circle
			(at 3.4671 -1.27)
			(size 1.0414 1.0414)
			(drill 1.0414)
			(layers "*.Cu" "*.Mask")
			(clearance 0.381)
			(thermal_gap 0.381)
		)
		(pad "" np_thru_hole circle
			(at 3.4671 1.27)
			(size 1.0414 1.0414)
			(drill 1.0414)
			(layers "*.Cu" "*.Mask")
			(clearance 0.381)
			(thermal_gap 0.381)
		)
		(pad "1" smd rect
			(at 0.8255 -0.249936)
			(size 0.3048 0.508)
			(layers "F.Cu" "F.Mask" "F.Paste")
			(net "85_10INCH_IN4_DP")
		)
		(pad "2" smd rect
			(at 0.8255 0.249936)
			(size 0.3048 0.508)
			(layers "F.Cu" "F.Mask" "F.Paste")
			(net "85_10INCH_IN4_DN")
		)
		(pad "3" smd circle
			(at 0 0 90)
			(size 0 0)
			(layers "F.Cu" "F.Mask" "F.Paste")
			(net "GND_P1")
		)
		(zone
			(layer "F.Cu")
			(hatch none 0.5)
			(connect_pads
				(clearance 0)
			)
			(min_thickness 0.25)
			(keepout
				(tracks not_allowed)
				(vias allowed)
				(pads allowed)
				(copperpour not_allowed)
				(footprints allowed)
			)
			(placement
				(enabled no)
				(sheetname "")
			)
			(fill
				(thermal_gap 0.5)
				(thermal_bridge_width 0.5)
				(island_removal_mode 0)
			)
			(polygon
				(pts
					(xy 95.362776 -17.013174) (xy 95.45828 -17.013174) (xy 95.45828 -16.416274) (xy 95.86468 -16.416274)
					(xy 95.86468 -17.013174) (xy 95.958152 -17.013174) (xy 95.958152 -16.416274) (xy 96.364552 -16.416274)
					(xy 96.364552 -17.013174) (xy 96.460056 -17.013174) (xy 96.460056 -16.314674) (xy 95.362776 -16.314674)
				)
			)
		)
		(zone
			(layers "F.Cu" "B.Cu" "In1.Cu" "In2.Cu" "In3.Cu" "In4.Cu" "In5.Cu" "In6.Cu"
				"In7.Cu" "In8.Cu" "In9.Cu" "In10.Cu"
			)
			(hatch none 0.5)
			(connect_pads
				(clearance 0)
			)
			(min_thickness 0.25)
			(keepout
				(tracks not_allowed)
				(vias allowed)
				(pads allowed)
				(copperpour not_allowed)
				(footprints allowed)
			)
			(placement
				(enabled no)
				(sheetname "")
			)
			(fill
				(thermal_gap 0.5)
				(thermal_bridge_width 0.5)
				(island_removal_mode 0)
			)
			(polygon
				(pts
					(arc
						(start 95.568516 -19.362674)
						(mid 93.714316 -19.362674)
						(end 95.568516 -19.362674)
					)
				)
			)
		)
		(zone
			(layers "F.Cu" "B.Cu" "In1.Cu" "In2.Cu" "In3.Cu" "In4.Cu" "In5.Cu" "In6.Cu"
				"In7.Cu" "In8.Cu" "In9.Cu" "In10.Cu"
			)
			(hatch none 0.5)
			(connect_pads
				(clearance 0)
			)
			(min_thickness 0.25)
			(keepout
				(tracks not_allowed)
				(vias allowed)
				(pads allowed)
				(copperpour not_allowed)
				(footprints allowed)
			)
			(placement
				(enabled no)
				(sheetname "")
			)
			(fill
				(thermal_gap 0.5)
				(thermal_bridge_width 0.5)
				(island_removal_mode 0)
			)
			(polygon
				(pts
					(arc
						(start 95.568516 -13.012674)
						(mid 93.714316 -13.012674)
						(end 95.568516 -13.012674)
					)
				)
			)
		)
		(zone
			(layers "F.Cu" "B.Cu" "In1.Cu" "In2.Cu" "In3.Cu" "In4.Cu" "In5.Cu" "In6.Cu"
				"In7.Cu" "In8.Cu" "In9.Cu" "In10.Cu"
			)
			(hatch none 0.5)
			(connect_pads
				(clearance 0)
			)
			(min_thickness 0.25)
			(keepout
				(tracks not_allowed)
				(vias allowed)
				(pads allowed)
				(copperpour not_allowed)
				(footprints allowed)
			)
			(placement
				(enabled no)
				(sheetname "")
			)
			(fill
				(thermal_gap 0.5)
				(thermal_bridge_width 0.5)
				(island_removal_mode 0)
			)
			(polygon
				(pts
					(arc
						(start 98.108516 -19.362674)
						(mid 96.254316 -19.362674)
						(end 98.108516 -19.362674)
					)
				)
			)
		)
		(zone
			(layers "F.Cu" "B.Cu" "In1.Cu" "In2.Cu" "In3.Cu" "In4.Cu" "In5.Cu" "In6.Cu"
				"In7.Cu" "In8.Cu" "In9.Cu" "In10.Cu"
			)
			(hatch none 0.5)
			(connect_pads
				(clearance 0)
			)
			(min_thickness 0.25)
			(keepout
				(tracks not_allowed)
				(vias allowed)
				(pads allowed)
				(copperpour not_allowed)
				(footprints allowed)
			)
			(placement
				(enabled no)
				(sheetname "")
			)
			(fill
				(thermal_gap 0.5)
				(thermal_bridge_width 0.5)
				(island_removal_mode 0)
			)
			(polygon
				(pts
					(arc
						(start 98.108516 -13.012674)
						(mid 96.254316 -13.012674)
						(end 98.108516 -13.012674)
					)
				)
			)
		)
	)
	(footprint ""
		(layer "F.Cu")
		(at 68.072 -11.43)
		(property "Reference" "U57"
			(at -0.463042 -1.674876 0)
			(unlocked yes)
			(layer "F.SilkS")
			(effects
				(font
					(size 0.7874 0.5842)
					(thickness 0.1524)
				)
				(justify left)
			)
		)
		(property "Value" ""
			(at 0 0 0)
			(layer "F.Fab")
			(effects
				(font
					(size 1.27 1.27)
				)
			)
		)
		(duplicate_pad_numbers_are_jumpers no)
		(fp_line
			(start -1.4986 -1.100074)
			(end 1.4986 -1.100074)
			(stroke
				(width 0.1524)
				(type default)
			)
			(layer "F.SilkS")
		)
		(fp_line
			(start -1.4986 1.100074)
			(end -1.4986 -1.100074)
			(stroke
				(width 0.1524)
				(type default)
			)
			(layer "F.SilkS")
		)
		(fp_line
			(start 1.4986 -1.100074)
			(end 1.4986 1.100074)
			(stroke
				(width 0.1524)
				(type default)
			)
			(layer "F.SilkS")
		)
		(fp_line
			(start 1.4986 1.100074)
			(end -1.4986 1.100074)
			(stroke
				(width 0.1524)
				(type default)
			)
			(layer "F.SilkS")
		)
		(fp_poly
			(pts
				(xy -2.20472 -0.338328) (xy -2.20472 -0.963168) (xy -1.651 -0.635)
			)
			(stroke
				(width 0)
				(type default)
			)
			(fill yes)
			(layer "F.SilkS")
		)
		(fp_line
			(start -0.67437 -1.100074)
			(end 0.67437 -1.100074)
			(stroke
				(width 0.1)
				(type default)
			)
			(layer "F.Fab")
		)
		(fp_line
			(start -0.67437 1.100074)
			(end -0.67437 -1.100074)
			(stroke
				(width 0.1)
				(type default)
			)
			(layer "F.Fab")
		)
		(fp_line
			(start 0.67437 -1.100074)
			(end 0.67437 1.100074)
			(stroke
				(width 0.1)
				(type default)
			)
			(layer "F.Fab")
		)
		(fp_line
			(start 0.67437 1.100074)
			(end -0.67437 1.100074)
			(stroke
				(width 0.1)
				(type default)
			)
			(layer "F.Fab")
		)
		(fp_poly
			(pts
				(xy -2.20472 -0.338328) (xy -2.20472 -0.963168) (xy -1.651 -0.635)
			)
			(stroke
				(width 0)
				(type default)
			)
			(fill yes)
			(layer "F.Fab")
		)
		(pad "1" smd rect
			(at -0.889 -0.649986)
			(size 1.016 0.381)
			(layers "F.Cu" "F.Mask" "F.Paste")
			(net "NC_U57_P1")
		)
		(pad "2" smd rect
			(at -0.889 0)
			(size 1.016 0.381)
			(layers "F.Cu" "F.Mask" "F.Paste")
			(net "REAR_AC_PWR_BMC_BTN_N")
		)
		(pad "3" smd rect
			(at -0.889 0.649986)
			(size 1.016 0.381)
			(layers "F.Cu" "F.Mask" "F.Paste")
			(net "GND")
		)
		(pad "4" smd rect
			(at 0.889 0.649986)
			(size 1.016 0.381)
			(layers "F.Cu" "F.Mask" "F.Paste")
			(net "AC_PWR_BMC_BTN_N")
		)
		(pad "5" smd rect
			(at 0.889 -0.649986)
			(size 1.016 0.381)
			(layers "F.Cu" "F.Mask" "F.Paste")
			(net "P3V3_AUX")
		)
	)
	(footprint ""
		(layer "F.Cu")
		(at 72.39 -19.685 90)
		(property "Reference" "R854"
			(at 0 0 90)
			(layer "F.SilkS")
			(hide yes)
			(effects
				(font
					(size 1.27 1.27)
				)
			)
		)
		(property "Value" ""
			(at 0 0 90)
			(layer "F.Fab")
			(effects
				(font
					(size 1.27 1.27)
				)
			)
		)
		(duplicate_pad_numbers_are_jumpers no)
		(fp_line
			(start 0.7874 -0.4064)
			(end 0.7874 0.4064)
			(stroke
				(width 0.1524)
				(type default)
			)
			(layer "F.SilkS")
		)
		(fp_line
			(start -0.7874 -0.4064)
			(end 0.7874 -0.4064)
			(stroke
				(width 0.1524)
				(type default)
			)
			(layer "F.SilkS")
		)
		(fp_line
			(start 0.7874 0.4064)
			(end -0.7874 0.4064)
			(stroke
				(width 0.1524)
				(type default)
			)
			(layer "F.SilkS")
		)
		(fp_line
			(start -0.7874 0.4064)
			(end -0.7874 -0.4064)
			(stroke
				(width 0.1524)
				(type default)
			)
			(layer "F.SilkS")
		)
		(fp_line
			(start -0.12065 -0.305054)
			(end -0.12065 -0.2794)
			(stroke
				(width 0.1)
				(type default)
			)
			(layer "F.Fab")
		)
		(fp_line
			(start -0.67945 -0.305054)
			(end -0.12065 -0.305054)
			(stroke
				(width 0.1)
				(type default)
			)
			(layer "F.Fab")
		)
		(fp_line
			(start 0.67945 -0.3048)
			(end 0.67945 0.3048)
			(stroke
				(width 0.1)
				(type default)
			)
			(layer "F.Fab")
		)
		(fp_line
			(start 0.12065 -0.3048)
			(end 0.67945 -0.3048)
			(stroke
				(width 0.1)
				(type default)
			)
			(layer "F.Fab")
		)
		(fp_line
			(start 0.12065 -0.2794)
			(end 0.12065 -0.3048)
			(stroke
				(width 0.1)
				(type default)
			)
			(layer "F.Fab")
		)
		(fp_line
			(start -0.12065 -0.2794)
			(end 0.12065 -0.2794)
			(stroke
				(width 0.1)
				(type default)
			)
			(layer "F.Fab")
		)
		(fp_line
			(start 0.120396 0.2794)
			(end -0.12065 0.2794)
			(stroke
				(width 0.1)
				(type default)
			)
			(layer "F.Fab")
		)
		(fp_line
			(start -0.12065 0.2794)
			(end -0.12065 0.3048)
			(stroke
				(width 0.1)
				(type default)
			)
			(layer "F.Fab")
		)
		(fp_line
			(start 0.67945 0.3048)
			(end 0.120396 0.3048)
			(stroke
				(width 0.1)
				(type default)
			)
			(layer "F.Fab")
		)
		(fp_line
			(start 0.120396 0.3048)
			(end 0.120396 0.2794)
			(stroke
				(width 0.1)
				(type default)
			)
			(layer "F.Fab")
		)
		(fp_line
			(start -0.12065 0.3048)
			(end -0.67945 0.3048)
			(stroke
				(width 0.1)
				(type default)
			)
			(layer "F.Fab")
		)
		(fp_line
			(start -0.67945 0.3048)
			(end -0.67945 -0.305054)
			(stroke
				(width 0.1)
				(type default)
			)
			(layer "F.Fab")
		)
		(pad "1" smd circle
			(at -0.40005 0 90)
			(size 0 0)
			(layers "F.Cu" "F.Mask" "F.Paste")
			(net "P1V8_AUX")
		)
		(pad "2" smd circle
			(at 0.40005 0 90)
			(size 0 0)
			(layers "F.Cu" "F.Mask" "F.Paste")
			(net "FM_BOARD_BMC_REV_ID2")
		)
	)
	(footprint ""
		(layer "F.Cu")
		(at 39.9415 -47.587916 180)
		(property "Reference" "R137"
			(at 0 0 180)
			(layer "F.SilkS")
			(hide yes)
			(effects
				(font
					(size 1.27 1.27)
				)
			)
		)
		(property "Value" ""
			(at 0 0 180)
			(layer "F.Fab")
			(effects
				(font
					(size 1.27 1.27)
				)
			)
		)
		(duplicate_pad_numbers_are_jumpers no)
		(fp_line
			(start 0.7874 0.4064)
			(end -0.7874 0.4064)
			(stroke
				(width 0.1524)
				(type default)
			)
			(layer "F.SilkS")
		)
		(fp_line
			(start 0.7874 -0.4064)
			(end 0.7874 0.4064)
			(stroke
				(width 0.1524)
				(type default)
			)
			(layer "F.SilkS")
		)
		(fp_line
			(start -0.7874 0.4064)
			(end -0.7874 -0.4064)
			(stroke
				(width 0.1524)
				(type default)
			)
			(layer "F.SilkS")
		)
		(fp_line
			(start -0.7874 -0.4064)
			(end 0.7874 -0.4064)
			(stroke
				(width 0.1524)
				(type default)
			)
			(layer "F.SilkS")
		)
		(fp_line
			(start 0.67945 0.3048)
			(end 0.120396 0.3048)
			(stroke
				(width 0.1)
				(type default)
			)
			(layer "F.Fab")
		)
		(fp_line
			(start 0.67945 -0.3048)
			(end 0.67945 0.3048)
			(stroke
				(width 0.1)
				(type default)
			)
			(layer "F.Fab")
		)
		(fp_line
			(start 0.12065 -0.2794)
			(end 0.12065 -0.3048)
			(stroke
				(width 0.1)
				(type default)
			)
			(layer "F.Fab")
		)
		(fp_line
			(start 0.12065 -0.3048)
			(end 0.67945 -0.3048)
			(stroke
				(width 0.1)
				(type default)
			)
			(layer "F.Fab")
		)
		(fp_line
			(start 0.120396 0.3048)
			(end 0.120396 0.2794)
			(stroke
				(width 0.1)
				(type default)
			)
			(layer "F.Fab")
		)
		(fp_line
			(start 0.120396 0.2794)
			(end -0.12065 0.2794)
			(stroke
				(width 0.1)
				(type default)
			)
			(layer "F.Fab")
		)
		(fp_line
			(start -0.12065 0.3048)
			(end -0.67945 0.3048)
			(stroke
				(width 0.1)
				(type default)
			)
			(layer "F.Fab")
		)
		(fp_line
			(start -0.12065 0.2794)
			(end -0.12065 0.3048)
			(stroke
				(width 0.1)
				(type default)
			)
			(layer "F.Fab")
		)
		(fp_line
			(start -0.12065 -0.2794)
			(end 0.12065 -0.2794)
			(stroke
				(width 0.1)
				(type default)
			)
			(layer "F.Fab")
		)
		(fp_line
			(start -0.12065 -0.305054)
			(end -0.12065 -0.2794)
			(stroke
				(width 0.1)
				(type default)
			)
			(layer "F.Fab")
		)
		(fp_line
			(start -0.67945 0.3048)
			(end -0.67945 -0.305054)
			(stroke
				(width 0.1)
				(type default)
			)
			(layer "F.Fab")
		)
		(fp_line
			(start -0.67945 -0.305054)
			(end -0.12065 -0.305054)
			(stroke
				(width 0.1)
				(type default)
			)
			(layer "F.Fab")
		)
		(pad "1" smd circle
			(at -0.40005 0 180)
			(size 0 0)
			(layers "F.Cu" "F.Mask" "F.Paste")
			(net "SMB_BMC_MM12_R_SCL")
		)
		(pad "2" smd circle
			(at 0.40005 0 180)
			(size 0 0)
			(layers "F.Cu" "F.Mask" "F.Paste")
			(net "SMB_BMC_MM12_SCL")
		)
	)
	(footprint ""
		(layer "F.Cu")
		(at 39.9288 -44.3992 180)
		(property "Reference" "R426"
			(at 0 0 180)
			(layer "F.SilkS")
			(hide yes)
			(effects
				(font
					(size 1.27 1.27)
				)
			)
		)
		(property "Value" ""
			(at 0 0 180)
			(layer "F.Fab")
			(effects
				(font
					(size 1.27 1.27)
				)
			)
		)
		(duplicate_pad_numbers_are_jumpers no)
		(fp_line
			(start 0.7874 0.4064)
			(end -0.7874 0.4064)
			(stroke
				(width 0.1524)
				(type default)
			)
			(layer "F.SilkS")
		)
		(fp_line
			(start 0.7874 -0.4064)
			(end 0.7874 0.4064)
			(stroke
				(width 0.1524)
				(type default)
			)
			(layer "F.SilkS")
		)
		(fp_line
			(start -0.7874 0.4064)
			(end -0.7874 -0.4064)
			(stroke
				(width 0.1524)
				(type default)
			)
			(layer "F.SilkS")
		)
		(fp_line
			(start -0.7874 -0.4064)
			(end 0.7874 -0.4064)
			(stroke
				(width 0.1524)
				(type default)
			)
			(layer "F.SilkS")
		)
		(fp_line
			(start 0.67945 0.3048)
			(end 0.120396 0.3048)
			(stroke
				(width 0.1)
				(type default)
			)
			(layer "F.Fab")
		)
		(fp_line
			(start 0.67945 -0.3048)
			(end 0.67945 0.3048)
			(stroke
				(width 0.1)
				(type default)
			)
			(layer "F.Fab")
		)
		(fp_line
			(start 0.12065 -0.2794)
			(end 0.12065 -0.3048)
			(stroke
				(width 0.1)
				(type default)
			)
			(layer "F.Fab")
		)
		(fp_line
			(start 0.12065 -0.3048)
			(end 0.67945 -0.3048)
			(stroke
				(width 0.1)
				(type default)
			)
			(layer "F.Fab")
		)
		(fp_line
			(start 0.120396 0.3048)
			(end 0.120396 0.2794)
			(stroke
				(width 0.1)
				(type default)
			)
			(layer "F.Fab")
		)
		(fp_line
			(start 0.120396 0.2794)
			(end -0.12065 0.2794)
			(stroke
				(width 0.1)
				(type default)
			)
			(layer "F.Fab")
		)
		(fp_line
			(start -0.12065 0.3048)
			(end -0.67945 0.3048)
			(stroke
				(width 0.1)
				(type default)
			)
			(layer "F.Fab")
		)
		(fp_line
			(start -0.12065 0.2794)
			(end -0.12065 0.3048)
			(stroke
				(width 0.1)
				(type default)
			)
			(layer "F.Fab")
		)
		(fp_line
			(start -0.12065 -0.2794)
			(end 0.12065 -0.2794)
			(stroke
				(width 0.1)
				(type default)
			)
			(layer "F.Fab")
		)
		(fp_line
			(start -0.12065 -0.305054)
			(end -0.12065 -0.2794)
			(stroke
				(width 0.1)
				(type default)
			)
			(layer "F.Fab")
		)
		(fp_line
			(start -0.67945 0.3048)
			(end -0.67945 -0.305054)
			(stroke
				(width 0.1)
				(type default)
			)
			(layer "F.Fab")
		)
		(fp_line
			(start -0.67945 -0.305054)
			(end -0.12065 -0.305054)
			(stroke
				(width 0.1)
				(type default)
			)
			(layer "F.Fab")
		)
		(pad "1" smd circle
			(at -0.40005 0 180)
			(size 0 0)
			(layers "F.Cu" "F.Mask" "F.Paste")
			(net "SMB_BMC_MM14_R_SDA")
		)
		(pad "2" smd circle
			(at 0.40005 0 180)
			(size 0 0)
			(layers "F.Cu" "F.Mask" "F.Paste")
			(net "SMB_BMC_MM14_SDA")
		)
	)
)
